(kicad_pcb
	(version 20241229)
	(generator "pcbnew")
	(generator_version "9.0")
	(general
		(thickness 1.61)
		(legacy_teardrops no)
	)
	(paper "A3")
	(title_block
		(title "RDIMM DDR5 Tester")
		(date "2026-05-21")
		(rev "2.2.0")
		(company "Antmicro")
		(comment 9 "footprint 109 of 796 (J2), pads 1-87 of 291")
	)
	(layers
		(0 "F.Cu" signal)
		(4 "In1.Cu" power)
		(6 "In2.Cu" mixed)
		(8 "In3.Cu" power)
		(10 "In4.Cu" mixed)
		(12 "In5.Cu" power)
		(14 "In6.Cu" mixed)
		(16 "In7.Cu" power)
		(18 "In8.Cu" power)
		(20 "In9.Cu" mixed)
		(22 "In10.Cu" power)
		(2 "B.Cu" signal)
		(9 "F.Adhes" user "F.Adhesive")
		(11 "B.Adhes" user "B.Adhesive")
		(13 "F.Paste" user)
		(15 "B.Paste" user)
		(5 "F.SilkS" user "F.Silkscreen")
		(7 "B.SilkS" user "B.Silkscreen")
		(1 "F.Mask" user)
		(3 "B.Mask" user)
		(17 "Dwgs.User" user "User.Drawings")
		(19 "Cmts.User" user "User.Comments")
		(21 "Eco1.User" user "User.Eco1")
		(23 "Eco2.User" user "User.Eco2")
		(25 "Edge.Cuts" user)
		(27 "Margin" user)
		(31 "F.CrtYd" user "F.Courtyard")
		(29 "B.CrtYd" user "B.Courtyard")
		(35 "F.Fab" user)
		(33 "B.Fab" user)
	)
	(footprint "antmicro-footprints:Bus_DDR5_Socket_Amphenol_DDR504111002KQ"
		(layer "F.Cu")
		(at 188.325 108.297 180)
		(descr "DIMM Connectors DDR5 SMD 288P")
		(property "Reference" "J2"
			(at 67.825 3.797 0)
			(layer "F.SilkS")
			(effects
				(font
					(size 0.7 0.7)
					(thickness 0.15)
				)
				(justify right bottom)
			)
		)
		(property "Value" "Bus_DDR5_DDR504111002KQ"
			(at 0 4.2 0)
			(layer "F.Fab")
			(effects
				(font
					(size 0.7 0.7)
					(thickness 0.15)
				)
				(justify right bottom)
			)
		)
		(property "Datasheet" "https://www.amphenol-icc.com/ddr5-smt-ddr504111002kq.html"
			(at 0 0 180)
			(layer "F.Fab")
			(hide yes)
			(effects
				(font
					(size 1.27 1.27)
					(thickness 0.15)
				)
			)
		)
		(property "Manufacturer" "Amphenol"
			(at 0 0 180)
			(unlocked yes)
			(layer "F.Fab")
			(hide yes)
			(effects
				(font
					(size 1 1)
					(thickness 0.15)
				)
			)
		)
		(property "MPN" "DDR504111002KQ"
			(at 0 0 180)
			(unlocked yes)
			(layer "F.Fab")
			(hide yes)
			(effects
				(font
					(size 1 1)
					(thickness 0.15)
				)
			)
		)
		(property "Author" "Antmicro"
			(at 0 0 180)
			(unlocked yes)
			(layer "F.Fab")
			(hide yes)
			(effects
				(font
					(size 1 1)
					(thickness 0.15)
				)
			)
		)
		(property "License" "Apache-2.0"
			(at 0 0 180)
			(unlocked yes)
			(layer "F.Fab")
			(hide yes)
			(effects
				(font
					(size 1 1)
					(thickness 0.15)
				)
			)
		)
		(sheetname "/DDR5 RDIMM/")
		(sheetfile "ddr5-rdimm.kicad_sch")
		(attr smd)
		(pad "1" smd rect
			(at -63.326 2.297 270)
			(size 1.8 0.57)
			(layers "F.Cu" "F.Mask" "F.Paste")
			(net 802 "/DDR5 RDIMM/VIN_BULK")
			(pinfunction "VIN_BULK")
			(pintype "power_in")
		)
		(pad "2" smd rect
			(at -62.476 2.297 270)
			(size 1.8 0.57)
			(layers "F.Cu" "F.Mask" "F.Paste")
			(net 308 "unconnected-(J2B-RFU-Pad2)")
			(pinfunction "RFU")
			(pintype "no_connect")
		)
		(pad "3" smd rect
			(at -61.625 2.297 270)
			(size 1.8 0.57)
			(layers "F.Cu" "F.Mask" "F.Paste")
			(net 803 "/DDR5 RDIMM/VIN_MGMT")
			(pinfunction "VIN_MGMT")
			(pintype "power_in")
		)
		(pad "4" smd rect
			(at -60.775 2.297 270)
			(size 1.8 0.57)
			(layers "F.Cu" "F.Mask" "F.Paste")
			(net 460 "/DDR5 RDIMM/DDR.SCL")
			(pinfunction "HSCL")
			(pintype "input")
		)
		(pad "5" smd rect
			(at -59.926 2.297 270)
			(size 1.8 0.57)
			(layers "F.Cu" "F.Mask" "F.Paste")
			(net 459 "/DDR5 RDIMM/DDR.SDA")
			(pinfunction "HSDA")
			(pintype "input")
		)
		(pad "6" smd rect
			(at -59.076 2.297 270)
			(size 1.8 0.57)
			(layers "F.Cu" "F.Mask" "F.Paste")
			(net 1 "GND")
			(pinfunction "VSS")
			(pintype "passive")
		)
		(pad "7" smd rect
			(at -58.226 2.297 270)
			(size 1.8 0.57)
			(layers "F.Cu" "F.Mask" "F.Paste")
			(net 51 "/DDR5 RDIMM/A.DQ0")
			(pinfunction "DQ0_A")
			(pintype "input")
		)
		(pad "8" smd rect
			(at -57.375 2.297 270)
			(size 1.8 0.57)
			(layers "F.Cu" "F.Mask" "F.Paste")
			(net 1 "GND")
			(pinfunction "VSS")
			(pintype "passive")
		)
		(pad "9" smd rect
			(at -56.525 2.297 270)
			(size 1.8 0.57)
			(layers "F.Cu" "F.Mask" "F.Paste")
			(net 52 "/DDR5 RDIMM/A.DQ1")
			(pinfunction "DQ1_A")
			(pintype "input")
		)
		(pad "10" smd rect
			(at -55.676 2.297 270)
			(size 1.8 0.57)
			(layers "F.Cu" "F.Mask" "F.Paste")
			(net 1 "GND")
			(pinfunction "VSS")
			(pintype "power_in")
		)
		(pad "11" smd rect
			(at -54.826 2.297 270)
			(size 1.8 0.57)
			(layers "F.Cu" "F.Mask" "F.Paste")
			(net 94 "/DDR5 RDIMM/A.DQS0_P")
			(pinfunction "DQS0_A_T")
			(pintype "input")
		)
		(pad "12" smd rect
			(at -53.976 2.297 270)
			(size 1.8 0.57)
			(layers "F.Cu" "F.Mask" "F.Paste")
			(net 101 "/DDR5 RDIMM/A.DQS0_N")
			(pinfunction "DQS0_A_C")
			(pintype "input")
		)
		(pad "13" smd rect
			(at -53.125 2.297 270)
			(size 1.8 0.57)
			(layers "F.Cu" "F.Mask" "F.Paste")
			(net 1 "GND")
			(pinfunction "VSS")
			(pintype "passive")
		)
		(pad "14" smd rect
			(at -52.275 2.297 270)
			(size 1.8 0.57)
			(layers "F.Cu" "F.Mask" "F.Paste")
			(net 53 "/DDR5 RDIMM/A.DQ4")
			(pinfunction "DQ4_A")
			(pintype "input")
		)
		(pad "15" smd rect
			(at -51.426 2.297 270)
			(size 1.8 0.57)
			(layers "F.Cu" "F.Mask" "F.Paste")
			(net 1 "GND")
			(pinfunction "VSS")
			(pintype "passive")
		)
		(pad "16" smd rect
			(at -50.576 2.297 270)
			(size 1.8 0.57)
			(layers "F.Cu" "F.Mask" "F.Paste")
			(net 54 "/DDR5 RDIMM/A.DQ5")
			(pinfunction "DQ5_A")
			(pintype "input")
		)
		(pad "17" smd rect
			(at -49.726 2.297 270)
			(size 1.8 0.57)
			(layers "F.Cu" "F.Mask" "F.Paste")
			(net 1 "GND")
			(pinfunction "VSS")
			(pintype "passive")
		)
		(pad "18" smd rect
			(at -48.875 2.297 270)
			(size 1.8 0.57)
			(layers "F.Cu" "F.Mask" "F.Paste")
			(net 55 "/DDR5 RDIMM/A.DQ8")
			(pinfunction "DQ8_A")
			(pintype "input")
		)
		(pad "19" smd rect
			(at -48.025 2.297 270)
			(size 1.8 0.57)
			(layers "F.Cu" "F.Mask" "F.Paste")
			(net 1 "GND")
			(pinfunction "VSS")
			(pintype "passive")
		)
		(pad "20" smd rect
			(at -47.176 2.297 270)
			(size 1.8 0.57)
			(layers "F.Cu" "F.Mask" "F.Paste")
			(net 56 "/DDR5 RDIMM/A.DQ9")
			(pinfunction "DQ9_A")
			(pintype "input")
		)
		(pad "21" smd rect
			(at -46.326 2.297 270)
			(size 1.8 0.57)
			(layers "F.Cu" "F.Mask" "F.Paste")
			(net 1 "GND")
			(pinfunction "VSS")
			(pintype "passive")
		)
		(pad "22" smd rect
			(at -45.476 2.297 270)
			(size 1.8 0.57)
			(layers "F.Cu" "F.Mask" "F.Paste")
			(net 102 "/DDR5 RDIMM/A.DQS1_P")
			(pinfunction "DQS1_A_T")
			(pintype "input")
		)
		(pad "23" smd rect
			(at -44.625 2.297 270)
			(size 1.8 0.57)
			(layers "F.Cu" "F.Mask" "F.Paste")
			(net 104 "/DDR5 RDIMM/A.DQS1_N")
			(pinfunction "DQS1_A_C")
			(pintype "input")
		)
		(pad "24" smd rect
			(at -43.775 2.297 270)
			(size 1.8 0.57)
			(layers "F.Cu" "F.Mask" "F.Paste")
			(net 1 "GND")
			(pinfunction "VSS")
			(pintype "passive")
		)
		(pad "25" smd rect
			(at -42.926 2.297 270)
			(size 1.8 0.57)
			(layers "F.Cu" "F.Mask" "F.Paste")
			(net 57 "/DDR5 RDIMM/A.DQ12")
			(pinfunction "DQ12_A")
			(pintype "input")
		)
		(pad "26" smd rect
			(at -42.076 2.297 270)
			(size 1.8 0.57)
			(layers "F.Cu" "F.Mask" "F.Paste")
			(net 1 "GND")
			(pinfunction "VSS")
			(pintype "passive")
		)
		(pad "27" smd rect
			(at -41.226 2.297 270)
			(size 1.8 0.57)
			(layers "F.Cu" "F.Mask" "F.Paste")
			(net 58 "/DDR5 RDIMM/A.DQ13")
			(pinfunction "DQ13_A")
			(pintype "input")
		)
		(pad "28" smd rect
			(at -40.375 2.297 270)
			(size 1.8 0.57)
			(layers "F.Cu" "F.Mask" "F.Paste")
			(net 1 "GND")
			(pinfunction "VSS")
			(pintype "passive")
		)
		(pad "29" smd rect
			(at -39.525 2.297 270)
			(size 1.8 0.57)
			(layers "F.Cu" "F.Mask" "F.Paste")
			(net 59 "/DDR5 RDIMM/A.DQ16")
			(pinfunction "DQ16_A")
			(pintype "input")
		)
		(pad "30" smd rect
			(at -38.676 2.297 270)
			(size 1.8 0.57)
			(layers "F.Cu" "F.Mask" "F.Paste")
			(net 1 "GND")
			(pinfunction "VSS")
			(pintype "passive")
		)
		(pad "31" smd rect
			(at -37.826 2.297 270)
			(size 1.8 0.57)
			(layers "F.Cu" "F.Mask" "F.Paste")
			(net 60 "/DDR5 RDIMM/A.DQ17")
			(pinfunction "DQ17_A")
			(pintype "input")
		)
		(pad "32" smd rect
			(at -36.976 2.297 270)
			(size 1.8 0.57)
			(layers "F.Cu" "F.Mask" "F.Paste")
			(net 1 "GND")
			(pinfunction "VSS")
			(pintype "passive")
		)
		(pad "33" smd rect
			(at -36.125 2.297 270)
			(size 1.8 0.57)
			(layers "F.Cu" "F.Mask" "F.Paste")
			(net 108 "/DDR5 RDIMM/A.DQS2_P")
			(pinfunction "DQS2_A_T")
			(pintype "input")
		)
		(pad "34" smd rect
			(at -35.275 2.297 270)
			(size 1.8 0.57)
			(layers "F.Cu" "F.Mask" "F.Paste")
			(net 109 "/DDR5 RDIMM/A.DQS2_N")
			(pinfunction "DQS2_A_C")
			(pintype "input")
		)
		(pad "35" smd rect
			(at -34.426 2.297 270)
			(size 1.8 0.57)
			(layers "F.Cu" "F.Mask" "F.Paste")
			(net 1 "GND")
			(pinfunction "VSS")
			(pintype "passive")
		)
		(pad "36" smd rect
			(at -33.576 2.297 270)
			(size 1.8 0.57)
			(layers "F.Cu" "F.Mask" "F.Paste")
			(net 61 "/DDR5 RDIMM/A.DQ20")
			(pinfunction "DQ20_A")
			(pintype "input")
		)
		(pad "37" smd rect
			(at -32.726 2.297 270)
			(size 1.8 0.57)
			(layers "F.Cu" "F.Mask" "F.Paste")
			(net 1 "GND")
			(pinfunction "VSS")
			(pintype "passive")
		)
		(pad "38" smd rect
			(at -31.875 2.297 270)
			(size 1.8 0.57)
			(layers "F.Cu" "F.Mask" "F.Paste")
			(net 62 "/DDR5 RDIMM/A.DQ21")
			(pinfunction "DQ21_A")
			(pintype "input")
		)
		(pad "39" smd rect
			(at -31.026 2.297 270)
			(size 1.8 0.57)
			(layers "F.Cu" "F.Mask" "F.Paste")
			(net 1 "GND")
			(pinfunction "VSS")
			(pintype "passive")
		)
		(pad "40" smd rect
			(at -30.177 2.297 270)
			(size 1.8 0.57)
			(layers "F.Cu" "F.Mask" "F.Paste")
			(net 63 "/DDR5 RDIMM/A.DQ24")
			(pinfunction "DQ24_A")
			(pintype "input")
		)
		(pad "41" smd rect
			(at -29.325 2.297 270)
			(size 1.8 0.57)
			(layers "F.Cu" "F.Mask" "F.Paste")
			(net 1 "GND")
			(pinfunction "VSS")
			(pintype "passive")
		)
		(pad "42" smd rect
			(at -28.476 2.297 270)
			(size 1.8 0.57)
			(layers "F.Cu" "F.Mask" "F.Paste")
			(net 64 "/DDR5 RDIMM/A.DQ25")
			(pinfunction "DQ25_A")
			(pintype "input")
		)
		(pad "43" smd rect
			(at -27.625 2.297 270)
			(size 1.8 0.57)
			(layers "F.Cu" "F.Mask" "F.Paste")
			(net 1 "GND")
			(pinfunction "VSS")
			(pintype "passive")
		)
		(pad "44" smd rect
			(at -26.776 2.297 270)
			(size 1.8 0.57)
			(layers "F.Cu" "F.Mask" "F.Paste")
			(net 114 "/DDR5 RDIMM/A.DQS3_P")
			(pinfunction "DQS3_A_T")
			(pintype "input")
		)
		(pad "45" smd rect
			(at -25.927 2.297 270)
			(size 1.8 0.57)
			(layers "F.Cu" "F.Mask" "F.Paste")
			(net 115 "/DDR5 RDIMM/A.DQS3_N")
			(pinfunction "DQS3_A_C")
			(pintype "input")
		)
		(pad "46" smd rect
			(at -25.075 2.297 270)
			(size 1.8 0.57)
			(layers "F.Cu" "F.Mask" "F.Paste")
			(net 1 "GND")
			(pinfunction "VSS")
			(pintype "passive")
		)
		(pad "47" smd rect
			(at -24.226 2.297 270)
			(size 1.8 0.57)
			(layers "F.Cu" "F.Mask" "F.Paste")
			(net 65 "/DDR5 RDIMM/A.DQ28")
			(pinfunction "DQ28_A")
			(pintype "input")
		)
		(pad "48" smd rect
			(at -23.375 2.297 270)
			(size 1.8 0.57)
			(layers "F.Cu" "F.Mask" "F.Paste")
			(net 1 "GND")
			(pinfunction "VSS")
			(pintype "passive")
		)
		(pad "49" smd rect
			(at -22.526 2.297 270)
			(size 1.8 0.57)
			(layers "F.Cu" "F.Mask" "F.Paste")
			(net 66 "/DDR5 RDIMM/A.DQ29")
			(pinfunction "DQ29_A")
			(pintype "input")
		)
		(pad "50" smd rect
			(at -21.677 2.297 270)
			(size 1.8 0.57)
			(layers "F.Cu" "F.Mask" "F.Paste")
			(net 1 "GND")
			(pinfunction "VSS")
			(pintype "passive")
		)
		(pad "51" smd rect
			(at -20.825 2.297 270)
			(size 1.8 0.57)
			(layers "F.Cu" "F.Mask" "F.Paste")
			(net 67 "/DDR5 RDIMM/A.CB0")
			(pinfunction "CB0_A")
			(pintype "input")
		)
		(pad "52" smd rect
			(at -19.976 2.297 270)
			(size 1.8 0.57)
			(layers "F.Cu" "F.Mask" "F.Paste")
			(net 1 "GND")
			(pinfunction "VSS")
			(pintype "passive")
		)
		(pad "53" smd rect
			(at -19.125 2.297 270)
			(size 1.8 0.57)
			(layers "F.Cu" "F.Mask" "F.Paste")
			(net 68 "/DDR5 RDIMM/A.CB1")
			(pinfunction "CB1_A")
			(pintype "input")
		)
		(pad "54" smd rect
			(at -18.276 2.297 270)
			(size 1.8 0.57)
			(layers "F.Cu" "F.Mask" "F.Paste")
			(net 1 "GND")
			(pinfunction "VSS")
			(pintype "passive")
		)
		(pad "55" smd rect
			(at -17.427 2.297 270)
			(size 1.8 0.57)
			(layers "F.Cu" "F.Mask" "F.Paste")
			(net 120 "/DDR5 RDIMM/A.DQS4_P")
			(pinfunction "DQS4_A_T")
			(pintype "input")
		)
		(pad "56" smd rect
			(at -16.575 2.297 270)
			(size 1.8 0.57)
			(layers "F.Cu" "F.Mask" "F.Paste")
			(net 121 "/DDR5 RDIMM/A.DQS4_N")
			(pinfunction "DQS4_A_C")
			(pintype "input")
		)
		(pad "57" smd rect
			(at -15.725 2.297 270)
			(size 1.8 0.57)
			(layers "F.Cu" "F.Mask" "F.Paste")
			(net 1 "GND")
			(pinfunction "VSS")
			(pintype "passive")
		)
		(pad "58" smd rect
			(at -14.875 2.297 270)
			(size 1.8 0.57)
			(layers "F.Cu" "F.Mask" "F.Paste")
			(net 70 "/DDR5 RDIMM/A.CB4")
			(pinfunction "CB4_A")
			(pintype "input")
		)
		(pad "59" smd rect
			(at -14.026 2.297 270)
			(size 1.8 0.57)
			(layers "F.Cu" "F.Mask" "F.Paste")
			(net 1 "GND")
			(pinfunction "VSS")
			(pintype "passive")
		)
		(pad "60" smd rect
			(at -13.176 2.297 270)
			(size 1.8 0.57)
			(layers "F.Cu" "F.Mask" "F.Paste")
			(net 71 "/DDR5 RDIMM/A.CB5")
			(pinfunction "CB5_A")
			(pintype "input")
		)
		(pad "61" smd rect
			(at -12.326 2.297 270)
			(size 1.8 0.57)
			(layers "F.Cu" "F.Mask" "F.Paste")
			(net 1 "GND")
			(pinfunction "VSS")
			(pintype "passive")
		)
		(pad "62" smd rect
			(at -11.475 2.297 270)
			(size 1.8 0.57)
			(layers "F.Cu" "F.Mask" "F.Paste")
			(net 72 "/DDR5 RDIMM/CTRL.~{ALERT}")
			(pinfunction "ALERT_N")
			(pintype "input")
		)
		(pad "63" smd rect
			(at -10.625 2.297 270)
			(size 1.8 0.57)
			(layers "F.Cu" "F.Mask" "F.Paste")
			(net 1 "GND")
			(pinfunction "VSS")
			(pintype "passive")
		)
		(pad "64" smd rect
			(at -9.776 2.297 270)
			(size 1.8 0.57)
			(layers "F.Cu" "F.Mask" "F.Paste")
			(net 73 "/DDR5 RDIMM/A.CS0_c")
			(pinfunction "CS0_A_N")
			(pintype "input")
		)
		(pad "65" smd rect
			(at -8.926 2.297 270)
			(size 1.8 0.57)
			(layers "F.Cu" "F.Mask" "F.Paste")
			(net 1 "GND")
			(pinfunction "VSS")
			(pintype "passive")
		)
		(pad "66" smd rect
			(at -8.075 2.297 270)
			(size 1.8 0.57)
			(layers "F.Cu" "F.Mask" "F.Paste")
			(net 74 "/DDR5 RDIMM/A.CA0")
			(pinfunction "CA0_A")
			(pintype "input")
		)
		(pad "67" smd rect
			(at -7.226 2.297 270)
			(size 1.8 0.57)
			(layers "F.Cu" "F.Mask" "F.Paste")
			(net 1 "GND")
			(pinfunction "VSS")
			(pintype "passive")
		)
		(pad "68" smd rect
			(at -6.375 2.297 270)
			(size 1.8 0.57)
			(layers "F.Cu" "F.Mask" "F.Paste")
			(net 75 "/DDR5 RDIMM/A.CA2")
			(pinfunction "CA2_A")
			(pintype "input")
		)
		(pad "69" smd rect
			(at -5.526 2.297 270)
			(size 1.8 0.57)
			(layers "F.Cu" "F.Mask" "F.Paste")
			(net 1 "GND")
			(pinfunction "VSS")
			(pintype "passive")
		)
		(pad "70" smd rect
			(at -4.675 2.297 270)
			(size 1.8 0.57)
			(layers "F.Cu" "F.Mask" "F.Paste")
			(net 76 "/DDR5 RDIMM/A.CA4")
			(pinfunction "CA4_A")
			(pintype "input")
		)
		(pad "71" smd rect
			(at -3.826 2.297 270)
			(size 1.8 0.57)
			(layers "F.Cu" "F.Mask" "F.Paste")
			(net 1 "GND")
			(pinfunction "VSS")
			(pintype "passive")
		)
		(pad "72" smd rect
			(at -2.976 2.297 270)
			(size 1.8 0.57)
			(layers "F.Cu" "F.Mask" "F.Paste")
			(net 77 "/DDR5 RDIMM/A.CA6")
			(pinfunction "CA6_A")
			(pintype "input")
		)
		(pad "73" smd rect
			(at -2.125 2.297 270)
			(size 1.8 0.57)
			(layers "F.Cu" "F.Mask" "F.Paste")
			(net 1 "GND")
			(pinfunction "VSS")
			(pintype "passive")
		)
		(pad "74" smd rect
			(at -1.276 2.297 270)
			(size 1.8 0.57)
			(layers "F.Cu" "F.Mask" "F.Paste")
			(net 78 "/DDR5 RDIMM/A.PAR")
			(pinfunction "PAR_A")
			(pintype "input")
		)
		(pad "75" smd rect
			(at -0.425 2.297 270)
			(size 1.8 0.57)
			(layers "F.Cu" "F.Mask" "F.Paste")
			(net 703 "/DDR5 RDIMM/VSS_DET1")
			(pinfunction "VSS_DET")
			(pintype "passive")
		)
		(pad "76" smd rect
			(at 5.525 2.297 270)
			(size 1.8 0.57)
			(layers "F.Cu" "F.Mask" "F.Paste")
			(net 79 "/DDR5 RDIMM/B.CA0")
			(pinfunction "CA0_B")
			(pintype "input")
		)
		(pad "77" smd rect
			(at 6.373 2.297 270)
			(size 1.8 0.57)
			(layers "F.Cu" "F.Mask" "F.Paste")
			(net 1 "GND")
			(pinfunction "VSS")
			(pintype "passive")
		)
		(pad "78" smd rect
			(at 7.224 2.297 270)
			(size 1.8 0.57)
			(layers "F.Cu" "F.Mask" "F.Paste")
			(net 80 "/DDR5 RDIMM/B.CA1")
			(pinfunction "CA2_B")
			(pintype "input")
		)
		(pad "79" smd rect
			(at 8.073 2.297 270)
			(size 1.8 0.57)
			(layers "F.Cu" "F.Mask" "F.Paste")
			(net 1 "GND")
			(pinfunction "VSS")
			(pintype "passive")
		)
		(pad "80" smd rect
			(at 8.925 2.297 270)
			(size 1.8 0.57)
			(layers "F.Cu" "F.Mask" "F.Paste")
			(net 81 "/DDR5 RDIMM/B.CA4")
			(pinfunction "CA4_B")
			(pintype "input")
		)
		(pad "81" smd rect
			(at 9.775 2.297 270)
			(size 1.8 0.57)
			(layers "F.Cu" "F.Mask" "F.Paste")
			(net 1 "GND")
			(pinfunction "VSS")
			(pintype "passive")
		)
		(pad "82" smd rect
			(at 10.624 2.297 270)
			(size 1.8 0.57)
			(layers "F.Cu" "F.Mask" "F.Paste")
			(net 82 "/DDR5 RDIMM/B.CA6")
			(pinfunction "CA6_B")
			(pintype "input")
		)
		(pad "83" smd rect
			(at 11.473 2.297 270)
			(size 1.8 0.57)
			(layers "F.Cu" "F.Mask" "F.Paste")
			(net 1 "GND")
			(pinfunction "VSS")
			(pintype "passive")
		)
		(pad "84" smd rect
			(at 12.323 2.297 270)
			(size 1.8 0.57)
			(layers "F.Cu" "F.Mask" "F.Paste")
			(net 83 "/DDR5 RDIMM/B.CS0_c")
			(pinfunction "CS0_B_N")
			(pintype "input")
		)
		(pad "85" smd rect
			(at 13.175 2.297 270)
			(size 1.8 0.57)
			(layers "F.Cu" "F.Mask" "F.Paste")
			(net 1 "GND")
			(pinfunction "VSS")
			(pintype "passive")
		)
		(pad "86" smd rect
			(at 14.025 2.297 270)
			(size 1.8 0.57)
			(layers "F.Cu" "F.Mask" "F.Paste")
			(net 84 "/DDR5 RDIMM/CTRL.DLBDQ")
			(pinfunction "DLBDQ")
			(pintype "input")
		)
		(pad "87" smd rect
			(at 14.874 2.297 270)
			(size 1.8 0.57)
			(layers "F.Cu" "F.Mask" "F.Paste")
			(net 85 "/DDR5 RDIMM/CTRL.DLBDQS")
			(pinfunction "DLBDQS")
			(pintype "input")
		)
	)
)
